# S9S_MB_2U (Grand Teton) — schematic netlist excerpt (pin names and nets, part order shuffled) for the footprints in the layout excerpt that follows; sources: Cadence DE-HDL packaged netlist, KiCad conversion of 03242023_DA0F0TMBIJ0_F0T_Motherboard_J_brd_V01_OCP.brd

R1688  Q_RES  100K 1% CHIP  pkg 0402LF  page 244 : A = P12V_AUX ; B = FM_COMP_P3V3_AUX_VIN
R779  Q_RES  150 1% CHIP  pkg 0402LF  page 131 : A = PVNN_TERM_CPU0 ; B = FM_CPU_FBRK_DEBUG_N

(kicad_pcb
	(version 20260206)
	(generator "pcbnew")
	(generator_version "10.0")
	(general
		(thickness 1.6)
		(legacy_teardrops no)
	)
	(paper "A4")
	(title_block
		(title "03242023_DA0F0TMBIJ0_F0T_Motherboard_J_brd_V01_OCP.brd")
		(comment 1 "Grand Teton / footprints 2718-2719 of 6105")
	)
	(layers
		(0 "F.Cu" signal "TOP")
		(4 "In1.Cu" signal "GND")
		(6 "In2.Cu" signal "IN1")
		(8 "In3.Cu" signal "GND1")
		(10 "In4.Cu" signal "IN2")
		(12 "In5.Cu" signal "GND2")
		(14 "In6.Cu" signal "IN3")
		(16 "In7.Cu" signal "GND3")
		(18 "In8.Cu" signal "VCC")
		(20 "In9.Cu" signal "VCC1")
		(22 "In10.Cu" signal "GND4")
		(24 "In11.Cu" signal "IN4")
		(26 "In12.Cu" signal "GND5")
		(28 "In13.Cu" signal "IN5")
		(30 "In14.Cu" signal "GND6")
		(32 "In15.Cu" signal "IN6")
		(34 "In16.Cu" signal "GND7")
		(2 "B.Cu" signal "BOTTOM")
		(9 "F.Adhes" user "F.Adhesive")
		(11 "B.Adhes" user "B.Adhesive")
		(13 "F.Paste" user "Package Geometry/Pastemask Top")
		(15 "B.Paste" user "Package Geometry/Pastemask Bottom")
		(5 "F.SilkS" user "Ref Des/Silkscreen Top")
		(7 "B.SilkS" user "Ref Des/Silkscreen Bottom")
		(1 "F.Mask" user "Board Geometry/Soldermask Top")
		(3 "B.Mask" user "Board Geometry/Soldermask Bottom")
		(17 "Dwgs.User" user "User.Drawings")
		(19 "Cmts.User" user "User.Comments")
		(21 "Eco1.User" user "User.Eco1")
		(23 "Eco2.User" user "User.Eco2")
		(25 "Edge.Cuts" user "Board Geometry/Outline")
		(27 "Margin" user)
		(31 "F.CrtYd" user "Package Geometry/Place Bound Top")
		(29 "B.CrtYd" user "Package Geometry/Place Bound Bottom")
		(35 "F.Fab" user "Ref Des/Assembly Top")
		(33 "B.Fab" user "Ref Des/Assembly Bottom")
	)
	(footprint ""
		(layer "F.Cu")
		(at 209.74558 -130.830828)
		(property "Reference" "R1688"
			(at 0 0 0)
			(layer "F.SilkS")
			(hide yes)
			(effects
				(font
					(size 1.27 1.27)
				)
			)
		)
		(property "Value" ""
			(at 0 0 0)
			(layer "F.Fab")
			(effects
				(font
					(size 1.27 1.27)
				)
			)
		)
		(duplicate_pad_numbers_are_jumpers no)
		(fp_line
			(start -0.7874 -0.4064)
			(end 0.7874 -0.4064)
			(stroke
				(width 0.1524)
				(type default)
			)
			(layer "F.SilkS")
		)
		(fp_line
			(start -0.7874 0.4064)
			(end -0.7874 -0.4064)
			(stroke
				(width 0.1524)
				(type default)
			)
			(layer "F.SilkS")
		)
		(fp_line
			(start 0.7874 -0.4064)
			(end 0.7874 0.4064)
			(stroke
				(width 0.1524)
				(type default)
			)
			(layer "F.SilkS")
		)
		(fp_line
			(start 0.7874 0.4064)
			(end -0.7874 0.4064)
			(stroke
				(width 0.1524)
				(type default)
			)
			(layer "F.SilkS")
		)
		(fp_line
			(start -0.67945 -0.305054)
			(end -0.12065 -0.305054)
			(stroke
				(width 0.1)
				(type default)
			)
			(layer "F.Fab")
		)
		(fp_line
			(start -0.67945 0.3048)
			(end -0.67945 -0.305054)
			(stroke
				(width 0.1)
				(type default)
			)
			(layer "F.Fab")
		)
		(fp_line
			(start -0.12065 -0.305054)
			(end -0.12065 -0.2794)
			(stroke
				(width 0.1)
				(type default)
			)
			(layer "F.Fab")
		)
		(fp_line
			(start -0.12065 -0.2794)
			(end 0.12065 -0.2794)
			(stroke
				(width 0.1)
				(type default)
			)
			(layer "F.Fab")
		)
		(fp_line
			(start -0.12065 0.2794)
			(end -0.12065 0.3048)
			(stroke
				(width 0.1)
				(type default)
			)
			(layer "F.Fab")
		)
		(fp_line
			(start -0.12065 0.3048)
			(end -0.67945 0.3048)
			(stroke
				(width 0.1)
				(type default)
			)
			(layer "F.Fab")
		)
		(fp_line
			(start 0.120396 0.2794)
			(end -0.12065 0.2794)
			(stroke
				(width 0.1)
				(type default)
			)
			(layer "F.Fab")
		)
		(fp_line
			(start 0.120396 0.3048)
			(end 0.120396 0.2794)
			(stroke
				(width 0.1)
				(type default)
			)
			(layer "F.Fab")
		)
		(fp_line
			(start 0.12065 -0.3048)
			(end 0.67945 -0.3048)
			(stroke
				(width 0.1)
				(type default)
			)
			(layer "F.Fab")
		)
		(fp_line
			(start 0.12065 -0.2794)
			(end 0.12065 -0.3048)
			(stroke
				(width 0.1)
				(type default)
			)
			(layer "F.Fab")
		)
		(fp_line
			(start 0.67945 -0.3048)
			(end 0.67945 0.3048)
			(stroke
				(width 0.1)
				(type default)
			)
			(layer "F.Fab")
		)
		(fp_line
			(start 0.67945 0.3048)
			(end 0.120396 0.3048)
			(stroke
				(width 0.1)
				(type default)
			)
			(layer "F.Fab")
		)
		(pad "1" smd circle
			(at -0.40005 0)
			(size 0 0)
			(layers "F.Cu" "F.Mask" "F.Paste")
			(net "P12V_AUX")
		)
		(pad "2" smd circle
			(at 0.40005 0)
			(size 0 0)
			(layers "F.Cu" "F.Mask" "F.Paste")
			(net "FM_COMP_P3V3_AUX_VIN")
		)
	)
	(footprint ""
		(layer "F.Cu")
		(at 370.4082 -92.954348 90)
		(property "Reference" "R779"
			(at 0 0 90)
			(layer "F.SilkS")
			(hide yes)
			(effects
				(font
					(size 1.27 1.27)
				)
			)
		)
		(property "Value" ""
			(at 0 0 90)
			(layer "F.Fab")
			(effects
				(font
					(size 1.27 1.27)
				)
			)
		)
		(duplicate_pad_numbers_are_jumpers no)
		(fp_line
			(start 0.7874 -0.4064)
			(end 0.7874 0.4064)
			(stroke
				(width 0.1524)
				(type default)
			)
			(layer "F.SilkS")
		)
		(fp_line
			(start -0.7874 -0.4064)
			(end 0.7874 -0.4064)
			(stroke
				(width 0.1524)
				(type default)
			)
			(layer "F.SilkS")
		)
		(fp_line
			(start 0.7874 0.4064)
			(end -0.7874 0.4064)
			(stroke
				(width 0.1524)
				(type default)
			)
			(layer "F.SilkS")
		)
		(fp_line
			(start -0.7874 0.4064)
			(end -0.7874 -0.4064)
			(stroke
				(width 0.1524)
				(type default)
			)
			(layer "F.SilkS")
		)
		(fp_line
			(start -0.12065 -0.305054)
			(end -0.12065 -0.2794)
			(stroke
				(width 0.1)
				(type default)
			)
			(layer "F.Fab")
		)
		(fp_line
			(start -0.67945 -0.305054)
			(end -0.12065 -0.305054)
			(stroke
				(width 0.1)
				(type default)
			)
			(layer "F.Fab")
		)
		(fp_line
			(start 0.67945 -0.3048)
			(end 0.67945 0.3048)
			(stroke
				(width 0.1)
				(type default)
			)
			(layer "F.Fab")
		)
		(fp_line
			(start 0.12065 -0.3048)
			(end 0.67945 -0.3048)
			(stroke
				(width 0.1)
				(type default)
			)
			(layer "F.Fab")
		)
		(fp_line
			(start 0.12065 -0.2794)
			(end 0.12065 -0.3048)
			(stroke
				(width 0.1)
				(type default)
			)
			(layer "F.Fab")
		)
		(fp_line
			(start -0.12065 -0.2794)
			(end 0.12065 -0.2794)
			(stroke
				(width 0.1)
				(type default)
			)
			(layer "F.Fab")
		)
		(fp_line
			(start 0.120396 0.2794)
			(end -0.12065 0.2794)
			(stroke
				(width 0.1)
				(type default)
			)
			(layer "F.Fab")
		)
		(fp_line
			(start -0.12065 0.2794)
			(end -0.12065 0.3048)
			(stroke
				(width 0.1)
				(type default)
			)
			(layer "F.Fab")
		)
		(fp_line
			(start 0.67945 0.3048)
			(end 0.120396 0.3048)
			(stroke
				(width 0.1)
				(type default)
			)
			(layer "F.Fab")
		)
		(fp_line
			(start 0.120396 0.3048)
			(end 0.120396 0.2794)
			(stroke
				(width 0.1)
				(type default)
			)
			(layer "F.Fab")
		)
		(fp_line
			(start -0.12065 0.3048)
			(end -0.67945 0.3048)
			(stroke
				(width 0.1)
				(type default)
			)
			(layer "F.Fab")
		)
		(fp_line
			(start -0.67945 0.3048)
			(end -0.67945 -0.305054)
			(stroke
				(width 0.1)
				(type default)
			)
			(layer "F.Fab")
		)
		(pad "1" smd circle
			(at -0.40005 0 90)
			(size 0 0)
			(layers "F.Cu" "F.Mask" "F.Paste")
			(net "PVNN_TERM_CPU0")
		)
		(pad "2" smd circle
			(at 0.40005 0 90)
			(size 0 0)
			(layers "F.Cu" "F.Mask" "F.Paste")
			(net "FM_CPU_FBRK_DEBUG_N")
		)
	)
)
